(kicad_pcb
	(version 20260206)
	(generator "pcbnew")
	(generator_version "10.0")
	(general
		(thickness 1.6)
		(legacy_teardrops no)
	)
	(paper "A4")
	(title_block
		(title "Bryce Canyon_F.DPB_16315-1-OCP.brd")
		(comment 1 "Bryce Canyon / footprints 183-187 of 2223")
	)
	(layers
		(0 "F.Cu" signal "TOP")
		(4 "In1.Cu" signal "L2GND")
		(6 "In2.Cu" signal "L3")
		(8 "In3.Cu" signal "L4GND")
		(10 "In4.Cu" signal "L5")
		(12 "In5.Cu" signal "L6VCC")
		(14 "In6.Cu" signal "L7VCC")
		(16 "In7.Cu" signal "L8")
		(18 "In8.Cu" signal "L9GND")
		(20 "In9.Cu" signal "L10")
		(22 "In10.Cu" signal "L11GND")
		(2 "B.Cu" signal "BOTTOM")
		(9 "F.Adhes" user "F.Adhesive")
		(11 "B.Adhes" user "B.Adhesive")
		(13 "F.Paste" user "Package Geometry/Pastemask Top")
		(15 "B.Paste" user "Package Geometry/Pastemask Bottom")
		(5 "F.SilkS" user "Ref Des/Silkscreen Top")
		(7 "B.SilkS" user "Ref Des/Silkscreen Bottom")
		(1 "F.Mask" user "Board Geometry/Soldermask Top")
		(3 "B.Mask" user "Board Geometry/Soldermask Bottom")
		(17 "Dwgs.User" user "User.Drawings")
		(19 "Cmts.User" user "User.Comments")
		(21 "Eco1.User" user "User.Eco1")
		(23 "Eco2.User" user "User.Eco2")
		(25 "Edge.Cuts" user "Board Geometry/Outline")
		(27 "Margin" user)
		(31 "F.CrtYd" user "Package Geometry/Place Bound Top")
		(29 "B.CrtYd" user "Package Geometry/Place Bound Bottom")
		(35 "F.Fab" user "Ref Des/Assembly Top")
		(33 "B.Fab" user "Ref Des/Assembly Bottom")
	)
	(footprint ""
		(layer "F.Cu")
		(at 370.1288 -139.5984 180)
		(property "Reference" "U24"
			(at 0 0 180)
			(layer "F.SilkS")
			(hide yes)
			(effects
				(font
					(size 1.27 1.27)
				)
			)
		)
		(property "Value" "ADM1278-2ACPZ-RL-1-GP"
			(at -4.7625 -7.4422 180)
			(unlocked yes)
			(layer "F.Fab")
			(hide yes)
			(effects
				(font
					(size 1.016 1.016)
					(thickness 0.1524)
				)
			)
		)
		(property "Device Type" "QFN32-G3D45-UH32"
			(at -4.7625 -8.9662 180)
			(unlocked yes)
			(layer "F.Fab")
			(hide yes)
			(effects
				(font
					(size 1.016 1.016)
					(thickness 0.1524)
				)
			)
		)
		(duplicate_pad_numbers_are_jumpers no)
		(fp_line
			(start 4.0513 -0.749808)
			(end 3.2893 -0.749808)
			(stroke
				(width 0.1524)
				(type default)
			)
			(layer "F.SilkS")
		)
		(fp_line
			(start 3.7973 1.749552)
			(end 3.2893 1.749552)
			(stroke
				(width 0.1524)
				(type default)
			)
			(layer "F.SilkS")
		)
		(fp_line
			(start 3.5179 3.5179)
			(end 2.2479 3.5179)
			(stroke
				(width 0.1524)
				(type default)
			)
			(layer "F.SilkS")
		)
		(fp_line
			(start 3.5179 2.2479)
			(end 3.5179 3.5179)
			(stroke
				(width 0.1524)
				(type default)
			)
			(layer "F.SilkS")
		)
		(fp_line
			(start -0.250698 4.0513)
			(end -0.250698 3.2893)
			(stroke
				(width 0.1524)
				(type default)
			)
			(layer "F.SilkS")
		)
		(fp_line
			(start -0.250698 -3.7973)
			(end -0.250698 -3.2893)
			(stroke
				(width 0.1524)
				(type default)
			)
			(layer "F.SilkS")
		)
		(fp_line
			(start -3.5179 3.5179)
			(end -2.2479 3.5179)
			(stroke
				(width 0.1524)
				(type default)
			)
			(layer "F.SilkS")
		)
		(fp_line
			(start -3.5179 2.2479)
			(end -3.5179 3.5179)
			(stroke
				(width 0.1524)
				(type default)
			)
			(layer "F.SilkS")
		)
		(fp_line
			(start -3.5179 -2.2479)
			(end -3.5179 -3.5179)
			(stroke
				(width 0.1524)
				(type default)
			)
			(layer "F.SilkS")
		)
		(fp_line
			(start -3.5179 -3.5179)
			(end -2.2479 -3.5179)
			(stroke
				(width 0.1524)
				(type default)
			)
			(layer "F.SilkS")
		)
		(fp_line
			(start -3.7973 1.24968)
			(end -3.2893 1.24968)
			(stroke
				(width 0.1524)
				(type default)
			)
			(layer "F.SilkS")
		)
		(fp_line
			(start -4.0513 -1.24968)
			(end -3.2893 -1.24968)
			(stroke
				(width 0.1524)
				(type default)
			)
			(layer "F.SilkS")
		)
		(fp_poly
			(pts
				(xy 2.2479 -3.5179) (xy 3.5179 -2.2479) (xy 3.5179 -3.5179)
			)
			(stroke
				(width 0)
				(type default)
			)
			(fill yes)
			(layer "F.SilkS")
		)
		(fp_rect
			(start -2.5019 2.5019)
			(end 2.5019 -2.5019)
			(stroke
				(width 0)
				(type default)
			)
			(fill no)
			(layer "F.CrtYd")
		)
		(fp_poly
			(pts
				(xy -3.5179 3.5179) (xy -3.5179 -3.5179) (xy 3.5179 -3.5179) (xy 3.5179 3.5179) (xy -2.49682 3.5179)
				(xy -2.49682 2.5019) (xy 2.5019 2.5019) (xy 2.5019 -2.5019) (xy -2.5019 -2.5019) (xy -2.5019 3.5179)
			)
			(stroke
				(width 0)
				(type default)
			)
			(fill no)
			(layer "F.CrtYd")
		)
		(fp_rect
			(start -3.5179 3.5179)
			(end 3.5179 -3.5179)
			(stroke
				(width 0)
				(type default)
			)
			(fill no)
			(layer "F.Fab")
		)
		(pad "1" smd rect
			(at 1.75006 -2.5527 180)
			(size 0.3048 0.9144)
			(layers "F.Cu" "F.Mask" "F.Paste")
			(net "MB1_PSET_R")
		)
		(pad "2" smd rect
			(at 1.249934 -2.4765 180)
			(size 0.3048 1.0668)
			(layers "F.Cu" "F.Mask" "F.Paste")
			(net "MB1_VCAP_R")
		)
		(pad "3" smd rect
			(at 0.750062 -2.4765 180)
			(size 0.3048 1.0668)
			(layers "F.Cu" "F.Mask" "F.Paste")
			(net "MB1_ISET_R")
		)
		(pad "4" smd rect
			(at 0.249936 -2.4765 180)
			(size 0.3048 1.0668)
			(layers "F.Cu" "F.Mask" "F.Paste")
			(net "MB1_ISTART_R")
		)
		(pad "5" smd rect
			(at -0.249936 -2.4765 180)
			(size 0.3048 1.0668)
			(layers "F.Cu" "F.Mask" "F.Paste")
			(net "MB1_TIME_R")
		)
		(pad "6" smd rect
			(at -0.750062 -2.4765 180)
			(size 0.3048 1.0668)
			(layers "F.Cu" "F.Mask" "F.Paste")
			(net "Net_1354")
		)
		(pad "7" smd rect
			(at -1.249934 -2.4765 180)
			(size 0.3048 1.0668)
			(layers "F.Cu" "F.Mask" "F.Paste")
			(net "MB1_CM_ADR1_R")
		)
		(pad "8" smd rect
			(at -1.75006 -2.5527 180)
			(size 0.3048 0.9144)
			(layers "F.Cu" "F.Mask" "F.Paste")
			(net "MB1_CM_ADR2_R")
		)
		(pad "9" smd rect
			(at -2.5527 -1.75006 180)
			(size 0.9144 0.3048)
			(layers "F.Cu" "F.Mask" "F.Paste")
			(net "MB1_SPISS_PD")
		)
		(pad "10" smd rect
			(at -2.4765 -1.249934 180)
			(size 1.0668 0.3048)
			(layers "F.Cu" "F.Mask" "F.Paste")
			(net "Net_1358")
		)
		(pad "11" smd rect
			(at -2.4765 -0.750062 180)
			(size 1.0668 0.3048)
			(layers "F.Cu" "F.Mask" "F.Paste")
			(net "Net_1357")
		)
		(pad "12" smd rect
			(at -2.4765 -0.249936 180)
			(size 1.0668 0.3048)
			(layers "F.Cu" "F.Mask" "F.Paste")
			(net "MB1_HS_ENABLE")
		)
		(pad "13" smd rect
			(at -2.4765 0.249936 180)
			(size 1.0668 0.3048)
			(layers "F.Cu" "F.Mask" "F.Paste")
			(net "Net_1356")
		)
		(pad "14" smd rect
			(at -2.4765 0.750062 180)
			(size 1.0668 0.3048)
			(layers "F.Cu" "F.Mask" "F.Paste")
			(net "Net_1355")
		)
		(pad "15" smd rect
			(at -2.4765 1.249934 180)
			(size 1.0668 0.3048)
			(layers "F.Cu" "F.Mask" "F.Paste")
			(net "MB1_SDA_R")
		)
		(pad "16" smd rect
			(at -2.5527 1.75006 180)
			(size 0.9144 0.3048)
			(layers "F.Cu" "F.Mask" "F.Paste")
			(net "MB1_SCL_R")
		)
		(pad "17" smd rect
			(at -1.75006 2.5527 180)
			(size 0.3048 0.9144)
			(layers "F.Cu" "F.Mask" "F.Paste")
			(net "MB1_RETRY_R")
		)
		(pad "18" smd rect
			(at -1.249934 2.4765 180)
			(size 0.3048 1.0668)
			(layers "F.Cu" "F.Mask" "F.Paste")
			(net "COMP_B_PGOOD")
		)
		(pad "19" smd rect
			(at -0.750062 2.4765 180)
			(size 0.3048 1.0668)
			(layers "F.Cu" "F.Mask" "F.Paste")
			(net "Net_1359")
		)
		(pad "20" smd rect
			(at -0.249936 2.4765 180)
			(size 0.3048 1.0668)
			(layers "F.Cu" "F.Mask" "F.Paste")
			(net "MB1_CM_VOUT_R")
		)
		(pad "21" smd rect
			(at 0.249936 2.4765 180)
			(size 0.3048 1.0668)
			(layers "F.Cu" "F.Mask" "F.Paste")
			(net "MB1_P12V_PWGIN_R")
		)
		(pad "22" smd rect
			(at 0.750062 2.4765 180)
			(size 0.3048 1.0668)
			(layers "F.Cu" "F.Mask" "F.Paste")
			(net "AGND_CURRENT_MONOB")
		)
		(pad "23" smd rect
			(at 1.249934 2.4765 180)
			(size 0.3048 1.0668)
			(layers "F.Cu" "F.Mask" "F.Paste")
			(net "GND")
		)
		(pad "24" smd rect
			(at 1.75006 2.5527 180)
			(size 0.3048 0.9144)
			(layers "F.Cu" "F.Mask" "F.Paste")
			(net "MB1_CM_GATE")
		)
		(pad "25" smd rect
			(at 2.5527 1.75006 180)
			(size 0.9144 0.3048)
			(layers "F.Cu" "F.Mask" "F.Paste")
			(net "MB1_TEMP")
		)
		(pad "26" smd rect
			(at 2.4765 1.249934 180)
			(size 1.0668 0.3048)
			(layers "F.Cu" "F.Mask" "F.Paste")
			(net "MB1_CM_SENSE_N")
		)
		(pad "27" smd rect
			(at 2.4765 0.750062 180)
			(size 1.0668 0.3048)
			(layers "F.Cu" "F.Mask" "F.Paste")
			(net "MB1_HS_SENSE_N")
		)
		(pad "28" smd rect
			(at 2.4765 0.249936 180)
			(size 1.0668 0.3048)
			(layers "F.Cu" "F.Mask" "F.Paste")
			(net "MB1_HS_SENSE_P")
		)
		(pad "29" smd rect
			(at 2.4765 -0.249936 180)
			(size 1.0668 0.3048)
			(layers "F.Cu" "F.Mask" "F.Paste")
			(net "MB1_CM_SENSE_P")
		)
		(pad "30" smd rect
			(at 2.4765 -0.750062 180)
			(size 1.0668 0.3048)
			(layers "F.Cu" "F.Mask" "F.Paste")
			(net "MB1_P12V_HS")
		)
		(pad "31" smd rect
			(at 2.4765 -1.249934 180)
			(size 1.0668 0.3048)
			(layers "F.Cu" "F.Mask" "F.Paste")
			(net "MB1_CM_UV_R")
		)
		(pad "32" smd rect
			(at 2.5527 -1.75006 180)
			(size 0.9144 0.3048)
			(layers "F.Cu" "F.Mask" "F.Paste")
			(net "MB1_CM_OV_R")
		)
		(pad "33" smd rect
			(at 0 0 180)
			(size 3.4544 3.4544)
			(layers "F.Cu" "F.Mask" "F.Paste")
			(net "AGND_CURRENT_MONOB")
		)
	)
	(footprint ""
		(layer "F.Cu")
		(at 141.042898 -283.507942 -90)
		(property "Reference" "R237"
			(at 0 0 270)
			(layer "F.SilkS")
			(hide yes)
			(effects
				(font
					(size 1.27 1.27)
				)
			)
		)
		(property "Value" "300KR2F-GP"
			(at 0.064008 -3.993896 270)
			(unlocked yes)
			(layer "F.Fab")
			(hide yes)
			(effects
				(font
					(size 1.016 1.016)
					(thickness 0.1524)
				)
			)
		)
		(property "Device Type" "R402H16"
			(at 0.064008 -5.517896 270)
			(unlocked yes)
			(layer "F.Fab")
			(hide yes)
			(effects
				(font
					(size 1.016 1.016)
					(thickness 0.1524)
				)
			)
		)
		(duplicate_pad_numbers_are_jumpers no)
		(fp_line
			(start -0.508 -0.9398)
			(end -0.508 0.9398)
			(stroke
				(width 0.1524)
				(type default)
			)
			(layer "F.SilkS")
		)
		(fp_line
			(start 0.508 -0.9398)
			(end -0.508 -0.9398)
			(stroke
				(width 0.1524)
				(type default)
			)
			(layer "F.SilkS")
		)
		(fp_rect
			(start -0.508 0.9398)
			(end 0.508 -0.9398)
			(stroke
				(width 0)
				(type default)
			)
			(fill no)
			(layer "F.CrtYd")
		)
		(fp_rect
			(start -0.508 0.9398)
			(end 0.508 -0.9398)
			(stroke
				(width 0)
				(type default)
			)
			(fill no)
			(layer "F.Fab")
		)
		(pad "1" smd custom
			(at 0 -0.4445 270)
			(size 0.1397 0.1397)
			(layers "F.Cu" "F.Mask" "F.Paste")
			(net "SW_HDD_N4")
			(options
				(clearance outline)
				(anchor circle)
			)
			(primitives
				(gr_poly
					(pts
						(arc
							(start -0.1778 -0.2794)
							(mid -0.249642 -0.249642)
							(end -0.2794 -0.1778)
						)
						(arc
							(start -0.2794 0.1778)
							(mid -0.249642 0.249642)
							(end -0.1778 0.2794)
						)
						(arc
							(start 0.1778 0.2794)
							(mid 0.249642 0.249642)
							(end 0.2794 0.1778)
						)
						(arc
							(start 0.2794 -0.1778)
							(mid 0.249642 -0.249642)
							(end 0.1778 -0.2794)
						)
					)
					(width 0)
					(fill yes)
				)
			)
		)
		(pad "2" smd custom
			(at 0 0.4445 270)
			(size 0.1397 0.1397)
			(layers "F.Cu" "F.Mask" "F.Paste")
			(net "P12V_A")
			(options
				(clearance outline)
				(anchor circle)
			)
			(primitives
				(gr_poly
					(pts
						(arc
							(start -0.1778 -0.2794)
							(mid -0.249642 -0.249642)
							(end -0.2794 -0.1778)
						)
						(arc
							(start -0.2794 0.1778)
							(mid -0.249642 0.249642)
							(end -0.1778 0.2794)
						)
						(arc
							(start 0.1778 0.2794)
							(mid 0.249642 0.249642)
							(end 0.2794 0.1778)
						)
						(arc
							(start 0.2794 -0.1778)
							(mid 0.249642 -0.249642)
							(end 0.1778 -0.2794)
						)
					)
					(width 0)
					(fill yes)
				)
			)
		)
	)
	(footprint ""
		(layer "F.Cu")
		(at 332.359 -180.826918 180)
		(property "Reference" "C275"
			(at 0 0 180)
			(layer "F.SilkS")
			(hide yes)
			(effects
				(font
					(size 1.27 1.27)
				)
			)
		)
		(property "Value" "SC10U16V6KX-2GP"
			(at -0.0762 -5.1308 180)
			(unlocked yes)
			(layer "F.Fab")
			(hide yes)
			(effects
				(font
					(size 1.016 1.016)
					(thickness 0.1524)
				)
			)
		)
		(property "Device Type" "C1206H71"
			(at -0.127 -6.6548 180)
			(unlocked yes)
			(layer "F.Fab")
			(hide yes)
			(effects
				(font
					(size 1.016 1.016)
					(thickness 0.1524)
				)
			)
		)
		(duplicate_pad_numbers_are_jumpers no)
		(fp_line
			(start 1.016 2.2352)
			(end -1.016 2.2352)
			(stroke
				(width 0.1524)
				(type default)
			)
			(layer "F.SilkS")
		)
		(fp_line
			(start 1.016 0.8382)
			(end 1.016 2.2352)
			(stroke
				(width 0.1524)
				(type default)
			)
			(layer "F.SilkS")
		)
		(fp_line
			(start 1.016 -2.2352)
			(end 1.016 -0.8382)
			(stroke
				(width 0.1524)
				(type default)
			)
			(layer "F.SilkS")
		)
		(fp_line
			(start -1.016 2.2352)
			(end -1.016 0.8382)
			(stroke
				(width 0.1524)
				(type default)
			)
			(layer "F.SilkS")
		)
		(fp_line
			(start -1.016 -0.8382)
			(end -1.016 -2.2352)
			(stroke
				(width 0.1524)
				(type default)
			)
			(layer "F.SilkS")
		)
		(fp_line
			(start -1.016 -2.2352)
			(end 1.016 -2.2352)
			(stroke
				(width 0.1524)
				(type default)
			)
			(layer "F.SilkS")
		)
		(fp_rect
			(start -1.0922 2.3114)
			(end 1.0922 -2.3114)
			(stroke
				(width 0)
				(type default)
			)
			(fill no)
			(layer "F.CrtYd")
		)
		(fp_poly
			(pts
				(xy 1.0922 -2.3114) (xy 1.0922 2.3114) (xy -1.0922 2.3114) (xy -1.0922 -2.3114)
			)
			(stroke
				(width 0)
				(type default)
			)
			(fill no)
			(layer "F.Fab")
		)
		(pad "1" smd rect
			(at 0 -1.397 180)
			(size 1.651 1.27)
			(layers "F.Cu" "F.Mask" "F.Paste")
			(net "P5V_HDD18")
		)
		(pad "2" smd rect
			(at 0 1.397 180)
			(size 1.651 1.27)
			(layers "F.Cu" "F.Mask" "F.Paste")
			(net "GND")
		)
	)
	(footprint ""
		(layer "F.Cu")
		(at 98.767646 -304.353468 180)
		(property "Reference" "R232"
			(at 0 0 180)
			(layer "F.SilkS")
			(hide yes)
			(effects
				(font
					(size 1.27 1.27)
				)
			)
		)
		(property "Value" "130R3F-GP"
			(at -0.0254 -2.5146 180)
			(unlocked yes)
			(layer "F.Fab")
			(hide yes)
			(effects
				(font
					(size 1.016 1.016)
					(thickness 0.1524)
				)
			)
		)
		(property "Device Type" "R603H22"
			(at -0.0254 -4.0386 180)
			(unlocked yes)
			(layer "F.Fab")
			(hide yes)
			(effects
				(font
					(size 1.016 1.016)
					(thickness 0.1524)
				)
			)
		)
		(duplicate_pad_numbers_are_jumpers no)
		(fp_line
			(start 0.2032 0)
			(end 0.4826 0)
			(stroke
				(width 0.2032)
				(type default)
			)
			(layer "F.SilkS")
		)
		(fp_line
			(start -0.4826 0)
			(end -0.2032 0)
			(stroke
				(width 0.2032)
				(type default)
			)
			(layer "F.SilkS")
		)
		(fp_rect
			(start -0.5842 1.3335)
			(end 0.5842 -1.3335)
			(stroke
				(width 0)
				(type default)
			)
			(fill no)
			(layer "F.CrtYd")
		)
		(fp_rect
			(start -0.5842 1.3335)
			(end 0.5842 -1.3335)
			(stroke
				(width 0)
				(type default)
			)
			(fill no)
			(layer "F.Fab")
		)
		(pad "1" smd custom
			(at 0 -0.762 180)
			(size 0.2159 0.2159)
			(layers "F.Cu" "F.Mask" "F.Paste")
			(net "P5V_B")
			(options
				(clearance outline)
				(anchor circle)
			)
			(primitives
				(gr_poly
					(pts
						(arc
							(start -0.3302 -0.4318)
							(mid -0.402042 -0.402042)
							(end -0.4318 -0.3302)
						)
						(arc
							(start -0.4318 0.3302)
							(mid -0.402042 0.402042)
							(end -0.3302 0.4318)
						)
						(arc
							(start 0.3302 0.4318)
							(mid 0.402042 0.402042)
							(end 0.4318 0.3302)
						)
						(arc
							(start 0.4318 -0.3302)
							(mid 0.402042 -0.402042)
							(end 0.3302 -0.4318)
						)
					)
					(width 0)
					(fill yes)
				)
			)
		)
		(pad "2" smd custom
			(at 0 0.762 180)
			(size 0.2159 0.2159)
			(layers "F.Cu" "F.Mask" "F.Paste")
			(net "FLT_HDD27")
			(options
				(clearance outline)
				(anchor circle)
			)
			(primitives
				(gr_poly
					(pts
						(arc
							(start -0.3302 -0.4318)
							(mid -0.402042 -0.402042)
							(end -0.4318 -0.3302)
						)
						(arc
							(start -0.4318 0.3302)
							(mid -0.402042 0.402042)
							(end -0.3302 0.4318)
						)
						(arc
							(start 0.3302 0.4318)
							(mid 0.402042 0.402042)
							(end 0.4318 0.3302)
						)
						(arc
							(start 0.4318 -0.3302)
							(mid 0.402042 -0.402042)
							(end 0.3302 -0.4318)
						)
					)
					(width 0)
					(fill yes)
				)
			)
		)
	)
	(footprint ""
		(layer "F.Cu")
		(at 431.581052 -160.735518 180)
		(property "Reference" "R627"
			(at 0 0 180)
			(layer "F.SilkS")
			(hide yes)
			(effects
				(font
					(size 1.27 1.27)
				)
			)
		)
		(property "Value" "4K7R2J-2-GP"
			(at 0.064008 -3.993896 180)
			(unlocked yes)
			(layer "F.Fab")
			(hide yes)
			(effects
				(font
					(size 1.016 1.016)
					(thickness 0.1524)
				)
			)
		)
		(property "Device Type" "R402H16"
			(at 0.064008 -5.517896 180)
			(unlocked yes)
			(layer "F.Fab")
			(hide yes)
			(effects
				(font
					(size 1.016 1.016)
					(thickness 0.1524)
				)
			)
		)
		(duplicate_pad_numbers_are_jumpers no)
		(fp_line
			(start 0.508 -0.9398)
			(end -0.508 -0.9398)
			(stroke
				(width 0.1524)
				(type default)
			)
			(layer "F.SilkS")
		)
		(fp_line
			(start -0.508 -0.9398)
			(end -0.508 0.9398)
			(stroke
				(width 0.1524)
				(type default)
			)
			(layer "F.SilkS")
		)
		(fp_rect
			(start -0.508 0.9398)
			(end 0.508 -0.9398)
			(stroke
				(width 0)
				(type default)
			)
			(fill no)
			(layer "F.CrtYd")
		)
		(fp_rect
			(start -0.508 0.9398)
			(end 0.508 -0.9398)
			(stroke
				(width 0)
				(type default)
			)
			(fill no)
			(layer "F.Fab")
		)
		(pad "1" smd custom
			(at 0 -0.4445 180)
			(size 0.1397 0.1397)
			(layers "F.Cu" "F.Mask" "F.Paste")
			(net "P12V_A")
			(options
				(clearance outline)
				(anchor circle)
			)
			(primitives
				(gr_poly
					(pts
						(arc
							(start -0.1778 -0.2794)
							(mid -0.249642 -0.249642)
							(end -0.2794 -0.1778)
						)
						(arc
							(start -0.2794 0.1778)
							(mid -0.249642 0.249642)
							(end -0.1778 0.2794)
						)
						(arc
							(start 0.1778 0.2794)
							(mid 0.249642 0.249642)
							(end 0.2794 0.1778)
						)
						(arc
							(start 0.2794 -0.1778)
							(mid 0.249642 -0.249642)
							(end 0.1778 -0.2794)
						)
					)
					(width 0)
					(fill yes)
				)
			)
		)
		(pad "2" smd custom
			(at 0 0.4445 180)
			(size 0.1397 0.1397)
			(layers "F.Cu" "F.Mask" "F.Paste")
			(net "SW_HDD_R21")
			(options
				(clearance outline)
				(anchor circle)
			)
			(primitives
				(gr_poly
					(pts
						(arc
							(start -0.1778 -0.2794)
							(mid -0.249642 -0.249642)
							(end -0.2794 -0.1778)
						)
						(arc
							(start -0.2794 0.1778)
							(mid -0.249642 0.249642)
							(end -0.1778 0.2794)
						)
						(arc
							(start 0.1778 0.2794)
							(mid 0.249642 0.249642)
							(end 0.2794 0.1778)
						)
						(arc
							(start 0.2794 -0.1778)
							(mid 0.249642 -0.249642)
							(end 0.1778 -0.2794)
						)
					)
					(width 0)
					(fill yes)
				)
			)
		)
	)
)
